# BASEBOARD_FAB2 (Tioga Pass) — schematic netlist excerpt (pin names and nets, part order shuffled) for the footprints in the layout excerpt that follows; sources: Cadence DE-HDL packaged netlist, KiCad conversion of Wiwynn_Tioga_Pass_MB.brd

R4W6  RES  4.75K 1% CHIP  pkg 0402  page 102 : A = P3V3_DB1200 ; B = FM_DB1200_PWRGD_R
R3P17  RES  49.9 1% CHIP  pkg 0402  page 211 : A = PVCCIO_CPU0 ; B = SVID_CLK0_CPU0_R
CT8  CAP  1000PF 50V 10% X7R  pkg 0402LF  page 227 : A = A_TSENSE_PVDDQ_KLM ; B = GND

(kicad_pcb
	(version 20260206)
	(generator "pcbnew")
	(generator_version "10.0")
	(general
		(thickness 1.6)
		(legacy_teardrops no)
	)
	(paper "A4")
	(title_block
		(title "Wiwynn_Tioga_Pass_MB.brd")
		(comment 1 "Tioga Pass / footprints 2940-2942 of 4770")
	)
	(layers
		(0 "F.Cu" signal "TOP")
		(4 "In1.Cu" signal "L2GND")
		(6 "In2.Cu" signal "L3")
		(8 "In3.Cu" signal "L4GND")
		(10 "In4.Cu" signal "L5")
		(12 "In5.Cu" signal "L6GND")
		(14 "In6.Cu" signal "L7VCC")
		(16 "In7.Cu" signal "L8VCC")
		(18 "In8.Cu" signal "L9GND")
		(20 "In9.Cu" signal "L10")
		(22 "In10.Cu" signal "L11GND")
		(24 "In11.Cu" signal "L12")
		(26 "In12.Cu" signal "L13GND")
		(2 "B.Cu" signal "BOTTOM")
		(9 "F.Adhes" user "F.Adhesive")
		(11 "B.Adhes" user "B.Adhesive")
		(13 "F.Paste" user "Package Geometry/Pastemask Top")
		(15 "B.Paste" user "Package Geometry/Pastemask Bottom")
		(5 "F.SilkS" user "Ref Des/Silkscreen Top")
		(7 "B.SilkS" user "Ref Des/Silkscreen Bottom")
		(1 "F.Mask" user "Board Geometry/Soldermask Top")
		(3 "B.Mask" user "Board Geometry/Soldermask Bottom")
		(17 "Dwgs.User" user "User.Drawings")
		(19 "Cmts.User" user "User.Comments")
		(21 "Eco1.User" user "User.Eco1")
		(23 "Eco2.User" user "User.Eco2")
		(25 "Edge.Cuts" user "Board Geometry/Outline")
		(27 "Margin" user)
		(31 "F.CrtYd" user "Package Geometry/Place Bound Top")
		(29 "B.CrtYd" user "Package Geometry/Place Bound Bottom")
		(35 "F.Fab" user "Ref Des/Assembly Top")
		(33 "B.Fab" user "Ref Des/Assembly Bottom")
	)
	(footprint ""
		(layer "B.Cu")
		(at 168.088818 -73.653396 180)
		(property "Reference" "R4W6"
			(at 0.8382 -0.67818 180)
			(unlocked yes)
			(layer "B.SilkS")
			(effects
				(font
					(size 0.4064 0.254)
					(thickness 0.1524)
				)
				(justify left mirror)
			)
		)
		(property "Value" ""
			(at 0 0 0)
			(layer "B.Fab")
			(effects
				(font
					(size 1.27 1.27)
				)
				(justify mirror)
			)
		)
		(duplicate_pad_numbers_are_jumpers no)
		(fp_poly
			(pts
				(xy 0.2794 -0.1016) (xy -0.2794 -0.1016) (xy -0.2794 0.9906) (xy 0.2794 0.9906)
			)
			(stroke
				(width 0)
				(type default)
			)
			(fill no)
			(layer "B.CrtYd")
		)
		(fp_line
			(start 0.2794 0.9906)
			(end -0.2794 0.9906)
			(stroke
				(width 0.1)
				(type default)
			)
			(layer "B.Fab")
		)
		(fp_line
			(start 0.2794 -0.1016)
			(end 0.2794 0.9906)
			(stroke
				(width 0.1)
				(type default)
			)
			(layer "B.Fab")
		)
		(fp_line
			(start -0.2794 0.9906)
			(end -0.2794 -0.1016)
			(stroke
				(width 0.1)
				(type default)
			)
			(layer "B.Fab")
		)
		(fp_line
			(start -0.2794 -0.1016)
			(end 0.2794 -0.1016)
			(stroke
				(width 0.1)
				(type default)
			)
			(layer "B.Fab")
		)
		(pad "1" smd rect
			(at 0 0)
			(size 0.508 0.508)
			(layers "B.Cu" "B.Mask" "B.Paste")
			(net "P3V3_DB1200")
		)
		(pad "2" smd rect
			(at 0 0.889)
			(size 0.508 0.508)
			(layers "B.Cu" "B.Mask" "B.Paste")
			(net "FM_DB1200_PWRGD_R")
		)
		(zone
			(layer "B.Cu")
			(hatch none 0.5)
			(connect_pads
				(clearance 0)
			)
			(min_thickness 0.25)
			(keepout
				(tracks not_allowed)
				(vias allowed)
				(pads allowed)
				(copperpour not_allowed)
				(footprints allowed)
			)
			(placement
				(enabled no)
				(sheetname "")
			)
			(fill
				(thermal_gap 0.5)
				(thermal_bridge_width 0.5)
				(island_removal_mode 0)
			)
			(polygon
				(pts
					(xy 167.834818 -74.288396) (xy 168.342818 -74.288396) (xy 168.342818 -73.907396) (xy 167.834818 -73.907396)
				)
			)
		)
		(zone
			(layer "B.Cu")
			(hatch none 0.5)
			(connect_pads
				(clearance 0)
			)
			(min_thickness 0.25)
			(keepout
				(tracks allowed)
				(vias not_allowed)
				(pads allowed)
				(copperpour not_allowed)
				(footprints allowed)
			)
			(placement
				(enabled no)
				(sheetname "")
			)
			(fill
				(thermal_gap 0.5)
				(thermal_bridge_width 0.5)
				(island_removal_mode 0)
			)
			(polygon
				(pts
					(xy 167.834818 -73.907396) (xy 168.342818 -73.907396) (xy 168.342818 -74.288396) (xy 167.834818 -74.288396)
				)
			)
		)
	)
	(footprint ""
		(layer "B.Cu")
		(at -0.6604 -137.7696)
		(property "Reference" "CT8"
			(at 0.8382 -0.84963 0)
			(unlocked yes)
			(layer "B.SilkS")
			(effects
				(font
					(size 0.7874 0.5842)
					(thickness 0.1524)
				)
				(justify left mirror)
			)
		)
		(property "Value" ""
			(at 0 0 0)
			(layer "B.Fab")
			(effects
				(font
					(size 1.27 1.27)
				)
				(justify mirror)
			)
		)
		(duplicate_pad_numbers_are_jumpers no)
		(fp_poly
			(pts
				(xy -0.3048 -0.1016) (xy -0.3048 0.9906) (xy 0.3048 0.9906) (xy 0.3048 -0.1016)
			)
			(stroke
				(width 0)
				(type default)
			)
			(fill no)
			(layer "B.CrtYd")
		)
		(fp_line
			(start -0.3048 -0.1016)
			(end 0.3048 -0.1016)
			(stroke
				(width 0.1)
				(type default)
			)
			(layer "B.Fab")
		)
		(fp_line
			(start -0.3048 0.9906)
			(end -0.3048 -0.1016)
			(stroke
				(width 0.1)
				(type default)
			)
			(layer "B.Fab")
		)
		(fp_line
			(start 0.3048 -0.1016)
			(end 0.3048 0.9906)
			(stroke
				(width 0.1)
				(type default)
			)
			(layer "B.Fab")
		)
		(fp_line
			(start 0.3048 0.9906)
			(end -0.3048 0.9906)
			(stroke
				(width 0.1)
				(type default)
			)
			(layer "B.Fab")
		)
		(pad "1" smd rect
			(at 0 0 180)
			(size 0.508 0.508)
			(layers "B.Cu" "B.Mask" "B.Paste")
			(net "A_TSENSE_PVDDQ_KLM")
		)
		(pad "2" smd rect
			(at 0 0.889 180)
			(size 0.508 0.508)
			(layers "B.Cu" "B.Mask" "B.Paste")
			(net "GND")
		)
		(zone
			(layer "B.Cu")
			(hatch none 0.5)
			(connect_pads
				(clearance 0)
			)
			(min_thickness 0.25)
			(keepout
				(tracks allowed)
				(vias not_allowed)
				(pads allowed)
				(copperpour not_allowed)
				(footprints allowed)
			)
			(placement
				(enabled no)
				(sheetname "")
			)
			(fill
				(thermal_gap 0.5)
				(thermal_bridge_width 0.5)
				(island_removal_mode 0)
			)
			(polygon
				(pts
					(xy -0.4064 -137.5156) (xy -0.9144 -137.5156) (xy -0.9144 -137.1346) (xy -0.4064 -137.1346)
				)
			)
		)
		(zone
			(layer "B.Cu")
			(hatch none 0.5)
			(connect_pads
				(clearance 0)
			)
			(min_thickness 0.25)
			(keepout
				(tracks not_allowed)
				(vias allowed)
				(pads allowed)
				(copperpour not_allowed)
				(footprints allowed)
			)
			(placement
				(enabled no)
				(sheetname "")
			)
			(fill
				(thermal_gap 0.5)
				(thermal_bridge_width 0.5)
				(island_removal_mode 0)
			)
			(polygon
				(pts
					(xy -0.4064 -137.1346) (xy -0.9144 -137.1346) (xy -0.9144 -137.5156) (xy -0.4064 -137.5156)
				)
			)
		)
	)
	(footprint ""
		(layer "B.Cu")
		(at 340.3092 -86.4362)
		(property "Reference" "R3P17"
			(at 0 0 0)
			(layer "B.SilkS")
			(hide yes)
			(effects
				(font
					(size 1.27 1.27)
				)
				(justify mirror)
			)
		)
		(property "Value" ""
			(at 0 0 0)
			(layer "B.Fab")
			(effects
				(font
					(size 1.27 1.27)
				)
				(justify mirror)
			)
		)
		(duplicate_pad_numbers_are_jumpers no)
		(fp_poly
			(pts
				(xy 0.2794 -0.1016) (xy -0.2794 -0.1016) (xy -0.2794 0.9906) (xy 0.2794 0.9906)
			)
			(stroke
				(width 0)
				(type default)
			)
			(fill no)
			(layer "B.CrtYd")
		)
		(fp_line
			(start -0.2794 -0.1016)
			(end 0.2794 -0.1016)
			(stroke
				(width 0.1)
				(type default)
			)
			(layer "B.Fab")
		)
		(fp_line
			(start -0.2794 0.9906)
			(end -0.2794 -0.1016)
			(stroke
				(width 0.1)
				(type default)
			)
			(layer "B.Fab")
		)
		(fp_line
			(start 0.2794 -0.1016)
			(end 0.2794 0.9906)
			(stroke
				(width 0.1)
				(type default)
			)
			(layer "B.Fab")
		)
		(fp_line
			(start 0.2794 0.9906)
			(end -0.2794 0.9906)
			(stroke
				(width 0.1)
				(type default)
			)
			(layer "B.Fab")
		)
		(pad "1" smd rect
			(at 0 0 180)
			(size 0.508 0.508)
			(layers "B.Cu" "B.Mask" "B.Paste")
			(net "PVCCIO_CPU0")
		)
		(pad "2" smd rect
			(at 0 0.889 180)
			(size 0.508 0.508)
			(layers "B.Cu" "B.Mask" "B.Paste")
			(net "SVID_CLK0_CPU0_R")
		)
		(zone
			(layer "B.Cu")
			(hatch none 0.5)
			(connect_pads
				(clearance 0)
			)
			(min_thickness 0.25)
			(keepout
				(tracks allowed)
				(vias not_allowed)
				(pads allowed)
				(copperpour not_allowed)
				(footprints allowed)
			)
			(placement
				(enabled no)
				(sheetname "")
			)
			(fill
				(thermal_gap 0.5)
				(thermal_bridge_width 0.5)
				(island_removal_mode 0)
			)
			(polygon
				(pts
					(xy 340.5632 -86.1822) (xy 340.0552 -86.1822) (xy 340.0552 -85.8012) (xy 340.5632 -85.8012)
				)
			)
		)
		(zone
			(layer "B.Cu")
			(hatch none 0.5)
			(connect_pads
				(clearance 0)
			)
			(min_thickness 0.25)
			(keepout
				(tracks not_allowed)
				(vias allowed)
				(pads allowed)
				(copperpour not_allowed)
				(footprints allowed)
			)
			(placement
				(enabled no)
				(sheetname "")
			)
			(fill
				(thermal_gap 0.5)
				(thermal_bridge_width 0.5)
				(island_removal_mode 0)
			)
			(polygon
				(pts
					(xy 340.5632 -85.8012) (xy 340.0552 -85.8012) (xy 340.0552 -86.1822) (xy 340.5632 -86.1822)
				)
			)
		)
	)
)
